(kicad_pcb
	(version 20260206)
	(generator "pcbnew")
	(generator_version "10.0")
	(general
		(thickness 1.6)
		(legacy_teardrops no)
	)
	(paper "A4")
	(title_block
		(title "01162023_DA0F0TEBIF0_F0T_Expander_BD_F_brd_V02_OCP.brd")
		(comment 1 "Grand Teton / footprints 3931-3937 of 9728")
	)
	(layers
		(0 "F.Cu" signal "TOP")
		(4 "In1.Cu" signal "GND")
		(6 "In2.Cu" signal "VCC")
		(8 "In3.Cu" signal "VCC1")
		(10 "In4.Cu" signal "GND1")
		(12 "In5.Cu" signal "IN1")
		(14 "In6.Cu" signal "GND2")
		(16 "In7.Cu" signal "IN2")
		(18 "In8.Cu" signal "GND3")
		(20 "In9.Cu" signal "IN3")
		(22 "In10.Cu" signal "GND4")
		(24 "In11.Cu" signal "IN4")
		(26 "In12.Cu" signal "GND5")
		(28 "In13.Cu" signal "IN5")
		(30 "In14.Cu" signal "GND6")
		(32 "In15.Cu" signal "IN6")
		(34 "In16.Cu" signal "GND7")
		(2 "B.Cu" signal "BOTTOM")
		(9 "F.Adhes" user "F.Adhesive")
		(11 "B.Adhes" user "B.Adhesive")
		(13 "F.Paste" user "Package Geometry/Pastemask Top")
		(15 "B.Paste" user "Package Geometry/Pastemask Bottom")
		(5 "F.SilkS" user "Ref Des/Silkscreen Top")
		(7 "B.SilkS" user "Ref Des/Silkscreen Bottom")
		(1 "F.Mask" user "Board Geometry/Soldermask Top")
		(3 "B.Mask" user "Board Geometry/Soldermask Bottom")
		(17 "Dwgs.User" user "User.Drawings")
		(19 "Cmts.User" user "User.Comments")
		(21 "Eco1.User" user "User.Eco1")
		(23 "Eco2.User" user "User.Eco2")
		(25 "Edge.Cuts" user "Board Geometry/Outline")
		(27 "Margin" user)
		(31 "F.CrtYd" user "Package Geometry/Place Bound Top")
		(29 "B.CrtYd" user "Package Geometry/Place Bound Bottom")
		(35 "F.Fab" user "Ref Des/Assembly Top")
		(33 "B.Fab" user "Ref Des/Assembly Bottom")
	)
	(footprint ""
		(layer "F.Cu")
		(at 387.082792 -141.87297)
		(property "Reference" "R338"
			(at 0 0 0)
			(layer "F.SilkS")
			(hide yes)
			(effects
				(font
					(size 1.27 1.27)
				)
			)
		)
		(property "Value" ""
			(at 0 0 0)
			(layer "F.Fab")
			(effects
				(font
					(size 1.27 1.27)
				)
			)
		)
		(duplicate_pad_numbers_are_jumpers no)
		(fp_line
			(start -0.7874 -0.4064)
			(end 0.7874 -0.4064)
			(stroke
				(width 0.1524)
				(type default)
			)
			(layer "F.SilkS")
		)
		(fp_line
			(start -0.7874 0.4064)
			(end -0.7874 -0.4064)
			(stroke
				(width 0.1524)
				(type default)
			)
			(layer "F.SilkS")
		)
		(fp_line
			(start 0.7874 -0.4064)
			(end 0.7874 0.4064)
			(stroke
				(width 0.1524)
				(type default)
			)
			(layer "F.SilkS")
		)
		(fp_line
			(start 0.7874 0.4064)
			(end -0.7874 0.4064)
			(stroke
				(width 0.1524)
				(type default)
			)
			(layer "F.SilkS")
		)
		(fp_line
			(start -0.67945 -0.305054)
			(end -0.12065 -0.305054)
			(stroke
				(width 0.1)
				(type default)
			)
			(layer "F.Fab")
		)
		(fp_line
			(start -0.67945 0.3048)
			(end -0.67945 -0.305054)
			(stroke
				(width 0.1)
				(type default)
			)
			(layer "F.Fab")
		)
		(fp_line
			(start -0.12065 -0.305054)
			(end -0.12065 -0.2794)
			(stroke
				(width 0.1)
				(type default)
			)
			(layer "F.Fab")
		)
		(fp_line
			(start -0.12065 -0.2794)
			(end 0.12065 -0.2794)
			(stroke
				(width 0.1)
				(type default)
			)
			(layer "F.Fab")
		)
		(fp_line
			(start -0.12065 0.2794)
			(end -0.12065 0.3048)
			(stroke
				(width 0.1)
				(type default)
			)
			(layer "F.Fab")
		)
		(fp_line
			(start -0.12065 0.3048)
			(end -0.67945 0.3048)
			(stroke
				(width 0.1)
				(type default)
			)
			(layer "F.Fab")
		)
		(fp_line
			(start 0.120396 0.2794)
			(end -0.12065 0.2794)
			(stroke
				(width 0.1)
				(type default)
			)
			(layer "F.Fab")
		)
		(fp_line
			(start 0.120396 0.3048)
			(end 0.120396 0.2794)
			(stroke
				(width 0.1)
				(type default)
			)
			(layer "F.Fab")
		)
		(fp_line
			(start 0.12065 -0.3048)
			(end 0.67945 -0.3048)
			(stroke
				(width 0.1)
				(type default)
			)
			(layer "F.Fab")
		)
		(fp_line
			(start 0.12065 -0.2794)
			(end 0.12065 -0.3048)
			(stroke
				(width 0.1)
				(type default)
			)
			(layer "F.Fab")
		)
		(fp_line
			(start 0.67945 -0.3048)
			(end 0.67945 0.3048)
			(stroke
				(width 0.1)
				(type default)
			)
			(layer "F.Fab")
		)
		(fp_line
			(start 0.67945 0.3048)
			(end 0.120396 0.3048)
			(stroke
				(width 0.1)
				(type default)
			)
			(layer "F.Fab")
		)
		(pad "1" smd circle
			(at -0.40005 0)
			(size 0 0)
			(layers "F.Cu" "F.Mask" "F.Paste")
			(net "NIC6_BIF1_N")
		)
		(pad "2" smd circle
			(at 0.40005 0)
			(size 0 0)
			(layers "F.Cu" "F.Mask" "F.Paste")
			(net "GND")
		)
	)
	(footprint ""
		(layer "F.Cu")
		(at 352.232214 -144.526)
		(property "Reference" "R4841"
			(at 0 0 0)
			(layer "F.SilkS")
			(hide yes)
			(effects
				(font
					(size 1.27 1.27)
				)
			)
		)
		(property "Value" ""
			(at 0 0 0)
			(layer "F.Fab")
			(effects
				(font
					(size 1.27 1.27)
				)
			)
		)
		(duplicate_pad_numbers_are_jumpers no)
		(fp_line
			(start -0.7874 -0.4064)
			(end 0.7874 -0.4064)
			(stroke
				(width 0.1524)
				(type default)
			)
			(layer "F.SilkS")
		)
		(fp_line
			(start -0.7874 0.4064)
			(end -0.7874 -0.4064)
			(stroke
				(width 0.1524)
				(type default)
			)
			(layer "F.SilkS")
		)
		(fp_line
			(start 0.7874 -0.4064)
			(end 0.7874 0.4064)
			(stroke
				(width 0.1524)
				(type default)
			)
			(layer "F.SilkS")
		)
		(fp_line
			(start 0.7874 0.4064)
			(end -0.7874 0.4064)
			(stroke
				(width 0.1524)
				(type default)
			)
			(layer "F.SilkS")
		)
		(fp_line
			(start -0.67945 -0.305054)
			(end -0.12065 -0.305054)
			(stroke
				(width 0.1)
				(type default)
			)
			(layer "F.Fab")
		)
		(fp_line
			(start -0.67945 0.3048)
			(end -0.67945 -0.305054)
			(stroke
				(width 0.1)
				(type default)
			)
			(layer "F.Fab")
		)
		(fp_line
			(start -0.12065 -0.305054)
			(end -0.12065 -0.2794)
			(stroke
				(width 0.1)
				(type default)
			)
			(layer "F.Fab")
		)
		(fp_line
			(start -0.12065 -0.2794)
			(end 0.12065 -0.2794)
			(stroke
				(width 0.1)
				(type default)
			)
			(layer "F.Fab")
		)
		(fp_line
			(start -0.12065 0.2794)
			(end -0.12065 0.3048)
			(stroke
				(width 0.1)
				(type default)
			)
			(layer "F.Fab")
		)
		(fp_line
			(start -0.12065 0.3048)
			(end -0.67945 0.3048)
			(stroke
				(width 0.1)
				(type default)
			)
			(layer "F.Fab")
		)
		(fp_line
			(start 0.120396 0.2794)
			(end -0.12065 0.2794)
			(stroke
				(width 0.1)
				(type default)
			)
			(layer "F.Fab")
		)
		(fp_line
			(start 0.120396 0.3048)
			(end 0.120396 0.2794)
			(stroke
				(width 0.1)
				(type default)
			)
			(layer "F.Fab")
		)
		(fp_line
			(start 0.12065 -0.3048)
			(end 0.67945 -0.3048)
			(stroke
				(width 0.1)
				(type default)
			)
			(layer "F.Fab")
		)
		(fp_line
			(start 0.12065 -0.2794)
			(end 0.12065 -0.3048)
			(stroke
				(width 0.1)
				(type default)
			)
			(layer "F.Fab")
		)
		(fp_line
			(start 0.67945 -0.3048)
			(end 0.67945 0.3048)
			(stroke
				(width 0.1)
				(type default)
			)
			(layer "F.Fab")
		)
		(fp_line
			(start 0.67945 0.3048)
			(end 0.120396 0.3048)
			(stroke
				(width 0.1)
				(type default)
			)
			(layer "F.Fab")
		)
		(pad "1" smd circle
			(at -0.40005 0)
			(size 0 0)
			(layers "F.Cu" "F.Mask" "F.Paste")
			(net "RST_PEX_NIC7_PERST_N")
		)
		(pad "2" smd circle
			(at 0.40005 0)
			(size 0 0)
			(layers "F.Cu" "F.Mask" "F.Paste")
			(net "RST_PEX_NIC7_PERST_R_N")
		)
	)
	(footprint ""
		(layer "F.Cu")
		(at 20.446492 -58.323734)
		(property "Reference" "PC367"
			(at 0 0 0)
			(layer "F.SilkS")
			(hide yes)
			(effects
				(font
					(size 1.27 1.27)
				)
			)
		)
		(property "Value" ""
			(at 0 0 0)
			(layer "F.Fab")
			(effects
				(font
					(size 1.27 1.27)
				)
			)
		)
		(duplicate_pad_numbers_are_jumpers no)
		(fp_line
			(start -1.524 -0.762)
			(end 1.524 -0.762)
			(stroke
				(width 0.1524)
				(type default)
			)
			(layer "F.SilkS")
		)
		(fp_line
			(start -1.524 0.762)
			(end -1.524 -0.762)
			(stroke
				(width 0.1524)
				(type default)
			)
			(layer "F.SilkS")
		)
		(fp_line
			(start 1.524 -0.762)
			(end 1.524 0.762)
			(stroke
				(width 0.1524)
				(type default)
			)
			(layer "F.SilkS")
		)
		(fp_line
			(start 1.524 0.762)
			(end -1.524 0.762)
			(stroke
				(width 0.1524)
				(type default)
			)
			(layer "F.SilkS")
		)
		(fp_line
			(start -1.1049 -0.724916)
			(end -1.1049 0.724916)
			(stroke
				(width 0.1)
				(type default)
			)
			(layer "F.Fab")
		)
		(fp_line
			(start -1.1049 0.724916)
			(end 1.1049 0.724916)
			(stroke
				(width 0.1)
				(type default)
			)
			(layer "F.Fab")
		)
		(fp_line
			(start 1.1049 -0.724916)
			(end -1.1049 -0.724916)
			(stroke
				(width 0.1)
				(type default)
			)
			(layer "F.Fab")
		)
		(fp_line
			(start 1.1049 0.724916)
			(end 1.1049 -0.724916)
			(stroke
				(width 0.1)
				(type default)
			)
			(layer "F.Fab")
		)
		(pad "1" smd rect
			(at -0.889 0 180)
			(size 1.016 1.27)
			(layers "F.Cu" "F.Mask" "F.Paste")
			(net "GND")
		)
		(pad "2" smd rect
			(at 0.889 0 180)
			(size 1.016 1.27)
			(layers "F.Cu" "F.Mask" "F.Paste")
			(net "P12V_AUX")
		)
	)
	(footprint ""
		(layer "F.Cu")
		(at 204.591158 -85.691472)
		(property "Reference" "R4358"
			(at 0 0 0)
			(layer "F.SilkS")
			(hide yes)
			(effects
				(font
					(size 1.27 1.27)
				)
			)
		)
		(property "Value" ""
			(at 0 0 0)
			(layer "F.Fab")
			(effects
				(font
					(size 1.27 1.27)
				)
			)
		)
		(duplicate_pad_numbers_are_jumpers no)
		(fp_line
			(start -0.7874 -0.4064)
			(end 0.7874 -0.4064)
			(stroke
				(width 0.1524)
				(type default)
			)
			(layer "F.SilkS")
		)
		(fp_line
			(start -0.7874 0.4064)
			(end -0.7874 -0.4064)
			(stroke
				(width 0.1524)
				(type default)
			)
			(layer "F.SilkS")
		)
		(fp_line
			(start 0.7874 -0.4064)
			(end 0.7874 0.4064)
			(stroke
				(width 0.1524)
				(type default)
			)
			(layer "F.SilkS")
		)
		(fp_line
			(start 0.7874 0.4064)
			(end -0.7874 0.4064)
			(stroke
				(width 0.1524)
				(type default)
			)
			(layer "F.SilkS")
		)
		(fp_line
			(start -0.67945 -0.305054)
			(end -0.12065 -0.305054)
			(stroke
				(width 0.1)
				(type default)
			)
			(layer "F.Fab")
		)
		(fp_line
			(start -0.67945 0.3048)
			(end -0.67945 -0.305054)
			(stroke
				(width 0.1)
				(type default)
			)
			(layer "F.Fab")
		)
		(fp_line
			(start -0.12065 -0.305054)
			(end -0.12065 -0.2794)
			(stroke
				(width 0.1)
				(type default)
			)
			(layer "F.Fab")
		)
		(fp_line
			(start -0.12065 -0.2794)
			(end 0.12065 -0.2794)
			(stroke
				(width 0.1)
				(type default)
			)
			(layer "F.Fab")
		)
		(fp_line
			(start -0.12065 0.2794)
			(end -0.12065 0.3048)
			(stroke
				(width 0.1)
				(type default)
			)
			(layer "F.Fab")
		)
		(fp_line
			(start -0.12065 0.3048)
			(end -0.67945 0.3048)
			(stroke
				(width 0.1)
				(type default)
			)
			(layer "F.Fab")
		)
		(fp_line
			(start 0.120396 0.2794)
			(end -0.12065 0.2794)
			(stroke
				(width 0.1)
				(type default)
			)
			(layer "F.Fab")
		)
		(fp_line
			(start 0.120396 0.3048)
			(end 0.120396 0.2794)
			(stroke
				(width 0.1)
				(type default)
			)
			(layer "F.Fab")
		)
		(fp_line
			(start 0.12065 -0.3048)
			(end 0.67945 -0.3048)
			(stroke
				(width 0.1)
				(type default)
			)
			(layer "F.Fab")
		)
		(fp_line
			(start 0.12065 -0.2794)
			(end 0.12065 -0.3048)
			(stroke
				(width 0.1)
				(type default)
			)
			(layer "F.Fab")
		)
		(fp_line
			(start 0.67945 -0.3048)
			(end 0.67945 0.3048)
			(stroke
				(width 0.1)
				(type default)
			)
			(layer "F.Fab")
		)
		(fp_line
			(start 0.67945 0.3048)
			(end 0.120396 0.3048)
			(stroke
				(width 0.1)
				(type default)
			)
			(layer "F.Fab")
		)
		(pad "1" smd circle
			(at -0.40005 0)
			(size 0 0)
			(layers "F.Cu" "F.Mask" "F.Paste")
			(net "P3V3_AUX")
		)
		(pad "2" smd circle
			(at 0.40005 0)
			(size 0 0)
			(layers "F.Cu" "F.Mask" "F.Paste")
			(net "RST_SSD_LED_IOEXP_R_N")
		)
	)
	(footprint ""
		(layer "F.Cu")
		(at 162.160712 -356.244906 90)
		(property "Reference" "C400"
			(at 0 0 90)
			(layer "F.SilkS")
			(hide yes)
			(effects
				(font
					(size 1.27 1.27)
				)
			)
		)
		(property "Value" ""
			(at 0 0 90)
			(layer "F.Fab")
			(effects
				(font
					(size 1.27 1.27)
				)
			)
		)
		(duplicate_pad_numbers_are_jumpers no)
		(fp_line
			(start 0.299974 -0.150114)
			(end 0.299974 0.150114)
			(stroke
				(width 0.1)
				(type default)
			)
			(layer "F.Fab")
		)
		(fp_line
			(start -0.299974 -0.150114)
			(end 0.299974 -0.150114)
			(stroke
				(width 0.1)
				(type default)
			)
			(layer "F.Fab")
		)
		(fp_line
			(start 0.299974 0.150114)
			(end -0.299974 0.150114)
			(stroke
				(width 0.1)
				(type default)
			)
			(layer "F.Fab")
		)
		(fp_line
			(start -0.299974 0.150114)
			(end -0.299974 -0.150114)
			(stroke
				(width 0.1)
				(type default)
			)
			(layer "F.Fab")
		)
		(pad "1" smd rect
			(at -0.2667 0 90)
			(size 0.3048 0.381)
			(layers "F.Cu" "F.Mask" "F.Paste")
			(net "P5E_PEX1_STN7_TX_DP<113>")
		)
		(pad "2" smd rect
			(at 0.2667 0 90)
			(size 0.3048 0.381)
			(layers "F.Cu" "F.Mask" "F.Paste")
			(net "P5E_PEX1_STN7_TX_C_DP<113>")
		)
	)
	(footprint ""
		(layer "F.Cu")
		(at 139.756642 -20.467574 180)
		(property "Reference" "R1661"
			(at 0 0 180)
			(layer "F.SilkS")
			(hide yes)
			(effects
				(font
					(size 1.27 1.27)
				)
			)
		)
		(property "Value" ""
			(at 0 0 180)
			(layer "F.Fab")
			(effects
				(font
					(size 1.27 1.27)
				)
			)
		)
		(duplicate_pad_numbers_are_jumpers no)
		(fp_line
			(start 0.7874 0.4064)
			(end -0.7874 0.4064)
			(stroke
				(width 0.1524)
				(type default)
			)
			(layer "F.SilkS")
		)
		(fp_line
			(start 0.7874 -0.4064)
			(end 0.7874 0.4064)
			(stroke
				(width 0.1524)
				(type default)
			)
			(layer "F.SilkS")
		)
		(fp_line
			(start -0.7874 0.4064)
			(end -0.7874 -0.4064)
			(stroke
				(width 0.1524)
				(type default)
			)
			(layer "F.SilkS")
		)
		(fp_line
			(start -0.7874 -0.4064)
			(end 0.7874 -0.4064)
			(stroke
				(width 0.1524)
				(type default)
			)
			(layer "F.SilkS")
		)
		(fp_line
			(start 0.67945 0.3048)
			(end 0.120396 0.3048)
			(stroke
				(width 0.1)
				(type default)
			)
			(layer "F.Fab")
		)
		(fp_line
			(start 0.67945 -0.3048)
			(end 0.67945 0.3048)
			(stroke
				(width 0.1)
				(type default)
			)
			(layer "F.Fab")
		)
		(fp_line
			(start 0.12065 -0.2794)
			(end 0.12065 -0.3048)
			(stroke
				(width 0.1)
				(type default)
			)
			(layer "F.Fab")
		)
		(fp_line
			(start 0.12065 -0.3048)
			(end 0.67945 -0.3048)
			(stroke
				(width 0.1)
				(type default)
			)
			(layer "F.Fab")
		)
		(fp_line
			(start 0.120396 0.3048)
			(end 0.120396 0.2794)
			(stroke
				(width 0.1)
				(type default)
			)
			(layer "F.Fab")
		)
		(fp_line
			(start 0.120396 0.2794)
			(end -0.12065 0.2794)
			(stroke
				(width 0.1)
				(type default)
			)
			(layer "F.Fab")
		)
		(fp_line
			(start -0.12065 0.3048)
			(end -0.67945 0.3048)
			(stroke
				(width 0.1)
				(type default)
			)
			(layer "F.Fab")
		)
		(fp_line
			(start -0.12065 0.2794)
			(end -0.12065 0.3048)
			(stroke
				(width 0.1)
				(type default)
			)
			(layer "F.Fab")
		)
		(fp_line
			(start -0.12065 -0.2794)
			(end 0.12065 -0.2794)
			(stroke
				(width 0.1)
				(type default)
			)
			(layer "F.Fab")
		)
		(fp_line
			(start -0.12065 -0.305054)
			(end -0.12065 -0.2794)
			(stroke
				(width 0.1)
				(type default)
			)
			(layer "F.Fab")
		)
		(fp_line
			(start -0.67945 0.3048)
			(end -0.67945 -0.305054)
			(stroke
				(width 0.1)
				(type default)
			)
			(layer "F.Fab")
		)
		(fp_line
			(start -0.67945 -0.305054)
			(end -0.12065 -0.305054)
			(stroke
				(width 0.1)
				(type default)
			)
			(layer "F.Fab")
		)
		(pad "1" smd circle
			(at -0.40005 0 180)
			(size 0 0)
			(layers "F.Cu" "F.Mask" "F.Paste")
			(net "P3V3_SSD4")
		)
		(pad "2" smd circle
			(at 0.40005 0 180)
			(size 0 0)
			(layers "F.Cu" "F.Mask" "F.Paste")
			(net "SMB_ISO_SSD4_SDA")
		)
	)
	(footprint ""
		(layer "F.Cu")
		(at 261.355078 -53.468524 90)
		(property "Reference" "PC557"
			(at 0 0 90)
			(layer "F.SilkS")
			(hide yes)
			(effects
				(font
					(size 1.27 1.27)
				)
			)
		)
		(property "Value" ""
			(at 0 0 90)
			(layer "F.Fab")
			(effects
				(font
					(size 1.27 1.27)
				)
			)
		)
		(duplicate_pad_numbers_are_jumpers no)
		(fp_line
			(start 1.524 -0.762)
			(end 1.524 0.762)
			(stroke
				(width 0.1524)
				(type default)
			)
			(layer "F.SilkS")
		)
		(fp_line
			(start -1.524 -0.762)
			(end 1.524 -0.762)
			(stroke
				(width 0.1524)
				(type default)
			)
			(layer "F.SilkS")
		)
		(fp_line
			(start 1.524 0.762)
			(end -1.524 0.762)
			(stroke
				(width 0.1524)
				(type default)
			)
			(layer "F.SilkS")
		)
		(fp_line
			(start -1.524 0.762)
			(end -1.524 -0.762)
			(stroke
				(width 0.1524)
				(type default)
			)
			(layer "F.SilkS")
		)
		(fp_line
			(start 1.1049 -0.724916)
			(end -1.1049 -0.724916)
			(stroke
				(width 0.1)
				(type default)
			)
			(layer "F.Fab")
		)
		(fp_line
			(start -1.1049 -0.724916)
			(end -1.1049 0.724916)
			(stroke
				(width 0.1)
				(type default)
			)
			(layer "F.Fab")
		)
		(fp_line
			(start 1.1049 0.724916)
			(end 1.1049 -0.724916)
			(stroke
				(width 0.1)
				(type default)
			)
			(layer "F.Fab")
		)
		(fp_line
			(start -1.1049 0.724916)
			(end 1.1049 0.724916)
			(stroke
				(width 0.1)
				(type default)
			)
			(layer "F.Fab")
		)
		(pad "1" smd rect
			(at -0.889 0 270)
			(size 1.016 1.27)
			(layers "F.Cu" "F.Mask" "F.Paste")
			(net "GND")
		)
		(pad "2" smd rect
			(at 0.889 0 270)
			(size 1.016 1.27)
			(layers "F.Cu" "F.Mask" "F.Paste")
			(net "P3V3_AUX")
		)
	)
)
